# S9S_MB_2U (Grand Teton) — schematic netlist excerpt (pin names and nets, part order shuffled) for the footprints in the layout excerpt that follows; sources: Cadence DE-HDL packaged netlist, KiCad conversion of 03242023_DA0F0TMBIJ0_F0T_Motherboard_J_brd_V01_OCP.brd

R1025  Q_RES  75 1% EMPTY  pkg 0402LF  page 182 : A = JTAG_DBP_CPU_GTL_TCK ; B = GND
PR3954  Q_RES  10K 1% CHIP  pkg 0402LF  page 193 : A = P12V_E1S_OV_FB_0 ; B = GND

(kicad_pcb
	(version 20260206)
	(generator "pcbnew")
	(generator_version "10.0")
	(general
		(thickness 1.6)
		(legacy_teardrops no)
	)
	(paper "A4")
	(title_block
		(title "03242023_DA0F0TMBIJ0_F0T_Motherboard_J_brd_V01_OCP.brd")
		(comment 1 "Grand Teton / footprints 4075-4076 of 6105")
	)
	(layers
		(0 "F.Cu" signal "TOP")
		(4 "In1.Cu" signal "GND")
		(6 "In2.Cu" signal "IN1")
		(8 "In3.Cu" signal "GND1")
		(10 "In4.Cu" signal "IN2")
		(12 "In5.Cu" signal "GND2")
		(14 "In6.Cu" signal "IN3")
		(16 "In7.Cu" signal "GND3")
		(18 "In8.Cu" signal "VCC")
		(20 "In9.Cu" signal "VCC1")
		(22 "In10.Cu" signal "GND4")
		(24 "In11.Cu" signal "IN4")
		(26 "In12.Cu" signal "GND5")
		(28 "In13.Cu" signal "IN5")
		(30 "In14.Cu" signal "GND6")
		(32 "In15.Cu" signal "IN6")
		(34 "In16.Cu" signal "GND7")
		(2 "B.Cu" signal "BOTTOM")
		(9 "F.Adhes" user "F.Adhesive")
		(11 "B.Adhes" user "B.Adhesive")
		(13 "F.Paste" user "Package Geometry/Pastemask Top")
		(15 "B.Paste" user "Package Geometry/Pastemask Bottom")
		(5 "F.SilkS" user "Ref Des/Silkscreen Top")
		(7 "B.SilkS" user "Ref Des/Silkscreen Bottom")
		(1 "F.Mask" user "Board Geometry/Soldermask Top")
		(3 "B.Mask" user "Board Geometry/Soldermask Bottom")
		(17 "Dwgs.User" user "User.Drawings")
		(19 "Cmts.User" user "User.Comments")
		(21 "Eco1.User" user "User.Eco1")
		(23 "Eco2.User" user "User.Eco2")
		(25 "Edge.Cuts" user "Board Geometry/Outline")
		(27 "Margin" user)
		(31 "F.CrtYd" user "Package Geometry/Place Bound Top")
		(29 "B.CrtYd" user "Package Geometry/Place Bound Bottom")
		(35 "F.Fab" user "Ref Des/Assembly Top")
		(33 "B.Fab" user "Ref Des/Assembly Bottom")
	)
	(footprint ""
		(layer "F.Cu")
		(at 346.964254 -24.66213 90)
		(property "Reference" "R1025"
			(at 0 0 90)
			(layer "F.SilkS")
			(hide yes)
			(effects
				(font
					(size 1.27 1.27)
				)
			)
		)
		(property "Value" ""
			(at 0 0 90)
			(layer "F.Fab")
			(effects
				(font
					(size 1.27 1.27)
				)
			)
		)
		(duplicate_pad_numbers_are_jumpers no)
		(fp_line
			(start 0.7874 -0.4064)
			(end 0.7874 0.4064)
			(stroke
				(width 0.1524)
				(type default)
			)
			(layer "F.SilkS")
		)
		(fp_line
			(start -0.7874 -0.4064)
			(end 0.7874 -0.4064)
			(stroke
				(width 0.1524)
				(type default)
			)
			(layer "F.SilkS")
		)
		(fp_line
			(start 0.7874 0.4064)
			(end -0.7874 0.4064)
			(stroke
				(width 0.1524)
				(type default)
			)
			(layer "F.SilkS")
		)
		(fp_line
			(start -0.7874 0.4064)
			(end -0.7874 -0.4064)
			(stroke
				(width 0.1524)
				(type default)
			)
			(layer "F.SilkS")
		)
		(fp_line
			(start -0.12065 -0.305054)
			(end -0.12065 -0.2794)
			(stroke
				(width 0.1)
				(type default)
			)
			(layer "F.Fab")
		)
		(fp_line
			(start -0.67945 -0.305054)
			(end -0.12065 -0.305054)
			(stroke
				(width 0.1)
				(type default)
			)
			(layer "F.Fab")
		)
		(fp_line
			(start 0.67945 -0.3048)
			(end 0.67945 0.3048)
			(stroke
				(width 0.1)
				(type default)
			)
			(layer "F.Fab")
		)
		(fp_line
			(start 0.12065 -0.3048)
			(end 0.67945 -0.3048)
			(stroke
				(width 0.1)
				(type default)
			)
			(layer "F.Fab")
		)
		(fp_line
			(start 0.12065 -0.2794)
			(end 0.12065 -0.3048)
			(stroke
				(width 0.1)
				(type default)
			)
			(layer "F.Fab")
		)
		(fp_line
			(start -0.12065 -0.2794)
			(end 0.12065 -0.2794)
			(stroke
				(width 0.1)
				(type default)
			)
			(layer "F.Fab")
		)
		(fp_line
			(start 0.120396 0.2794)
			(end -0.12065 0.2794)
			(stroke
				(width 0.1)
				(type default)
			)
			(layer "F.Fab")
		)
		(fp_line
			(start -0.12065 0.2794)
			(end -0.12065 0.3048)
			(stroke
				(width 0.1)
				(type default)
			)
			(layer "F.Fab")
		)
		(fp_line
			(start 0.67945 0.3048)
			(end 0.120396 0.3048)
			(stroke
				(width 0.1)
				(type default)
			)
			(layer "F.Fab")
		)
		(fp_line
			(start 0.120396 0.3048)
			(end 0.120396 0.2794)
			(stroke
				(width 0.1)
				(type default)
			)
			(layer "F.Fab")
		)
		(fp_line
			(start -0.12065 0.3048)
			(end -0.67945 0.3048)
			(stroke
				(width 0.1)
				(type default)
			)
			(layer "F.Fab")
		)
		(fp_line
			(start -0.67945 0.3048)
			(end -0.67945 -0.305054)
			(stroke
				(width 0.1)
				(type default)
			)
			(layer "F.Fab")
		)
		(pad "1" smd circle
			(at -0.40005 0 90)
			(size 0 0)
			(layers "F.Cu" "F.Mask" "F.Paste")
			(net "JTAG_DBP_CPU_GTL_TCK")
		)
		(pad "2" smd circle
			(at 0.40005 0 90)
			(size 0 0)
			(layers "F.Cu" "F.Mask" "F.Paste")
			(net "GND")
		)
	)
	(footprint ""
		(layer "F.Cu")
		(at 252.961648 -54.161182 180)
		(property "Reference" "PR3954"
			(at 0 0 180)
			(layer "F.SilkS")
			(hide yes)
			(effects
				(font
					(size 1.27 1.27)
				)
			)
		)
		(property "Value" ""
			(at 0 0 180)
			(layer "F.Fab")
			(effects
				(font
					(size 1.27 1.27)
				)
			)
		)
		(duplicate_pad_numbers_are_jumpers no)
		(fp_line
			(start 0.7874 0.4064)
			(end -0.7874 0.4064)
			(stroke
				(width 0.1524)
				(type default)
			)
			(layer "F.SilkS")
		)
		(fp_line
			(start 0.7874 -0.4064)
			(end 0.7874 0.4064)
			(stroke
				(width 0.1524)
				(type default)
			)
			(layer "F.SilkS")
		)
		(fp_line
			(start -0.7874 0.4064)
			(end -0.7874 -0.4064)
			(stroke
				(width 0.1524)
				(type default)
			)
			(layer "F.SilkS")
		)
		(fp_line
			(start -0.7874 -0.4064)
			(end 0.7874 -0.4064)
			(stroke
				(width 0.1524)
				(type default)
			)
			(layer "F.SilkS")
		)
		(fp_line
			(start 0.67945 0.3048)
			(end 0.120396 0.3048)
			(stroke
				(width 0.1)
				(type default)
			)
			(layer "F.Fab")
		)
		(fp_line
			(start 0.67945 -0.3048)
			(end 0.67945 0.3048)
			(stroke
				(width 0.1)
				(type default)
			)
			(layer "F.Fab")
		)
		(fp_line
			(start 0.12065 -0.2794)
			(end 0.12065 -0.3048)
			(stroke
				(width 0.1)
				(type default)
			)
			(layer "F.Fab")
		)
		(fp_line
			(start 0.12065 -0.3048)
			(end 0.67945 -0.3048)
			(stroke
				(width 0.1)
				(type default)
			)
			(layer "F.Fab")
		)
		(fp_line
			(start 0.120396 0.3048)
			(end 0.120396 0.2794)
			(stroke
				(width 0.1)
				(type default)
			)
			(layer "F.Fab")
		)
		(fp_line
			(start 0.120396 0.2794)
			(end -0.12065 0.2794)
			(stroke
				(width 0.1)
				(type default)
			)
			(layer "F.Fab")
		)
		(fp_line
			(start -0.12065 0.3048)
			(end -0.67945 0.3048)
			(stroke
				(width 0.1)
				(type default)
			)
			(layer "F.Fab")
		)
		(fp_line
			(start -0.12065 0.2794)
			(end -0.12065 0.3048)
			(stroke
				(width 0.1)
				(type default)
			)
			(layer "F.Fab")
		)
		(fp_line
			(start -0.12065 -0.2794)
			(end 0.12065 -0.2794)
			(stroke
				(width 0.1)
				(type default)
			)
			(layer "F.Fab")
		)
		(fp_line
			(start -0.12065 -0.305054)
			(end -0.12065 -0.2794)
			(stroke
				(width 0.1)
				(type default)
			)
			(layer "F.Fab")
		)
		(fp_line
			(start -0.67945 0.3048)
			(end -0.67945 -0.305054)
			(stroke
				(width 0.1)
				(type default)
			)
			(layer "F.Fab")
		)
		(fp_line
			(start -0.67945 -0.305054)
			(end -0.12065 -0.305054)
			(stroke
				(width 0.1)
				(type default)
			)
			(layer "F.Fab")
		)
		(pad "1" smd circle
			(at -0.40005 0 180)
			(size 0 0)
			(layers "F.Cu" "F.Mask" "F.Paste")
			(net "P12V_E1S_OV_FB_0")
		)
		(pad "2" smd circle
			(at 0.40005 0 180)
			(size 0 0)
			(layers "F.Cu" "F.Mask" "F.Paste")
			(net "GND")
		)
	)
)
